# BASEBOARD_FAB2 (Tioga Pass) — schematic netlist excerpt (pin names and nets, part order shuffled) for the footprints in the layout excerpt that follows; sources: Cadence DE-HDL packaged netlist, KiCad conversion of Wiwynn_Tioga_Pass_MB.brd

C8F8  ST470U6D3VDM-7-GP  IRP=1.7A  pkg SMD-TCG4  page 240 : \1\ = P3V3_STBY ; \2\ = GND
C7G38  CAP  0.220UF 16V 10% X7R  pkg 0402  page 216 : A = VR_PVDDQ_ABC_PH2_BOOT ; B = VR_PVDDQ_ABC_PH2_PHASE

(kicad_pcb
	(version 20260206)
	(generator "pcbnew")
	(generator_version "10.0")
	(general
		(thickness 1.6)
		(legacy_teardrops no)
	)
	(paper "A4")
	(title_block
		(title "Wiwynn_Tioga_Pass_MB.brd")
		(comment 1 "Tioga Pass / footprints 1553-1554 of 4770")
	)
	(layers
		(0 "F.Cu" signal "TOP")
		(4 "In1.Cu" signal "L2GND")
		(6 "In2.Cu" signal "L3")
		(8 "In3.Cu" signal "L4GND")
		(10 "In4.Cu" signal "L5")
		(12 "In5.Cu" signal "L6GND")
		(14 "In6.Cu" signal "L7VCC")
		(16 "In7.Cu" signal "L8VCC")
		(18 "In8.Cu" signal "L9GND")
		(20 "In9.Cu" signal "L10")
		(22 "In10.Cu" signal "L11GND")
		(24 "In11.Cu" signal "L12")
		(26 "In12.Cu" signal "L13GND")
		(2 "B.Cu" signal "BOTTOM")
		(9 "F.Adhes" user "F.Adhesive")
		(11 "B.Adhes" user "B.Adhesive")
		(13 "F.Paste" user "Package Geometry/Pastemask Top")
		(15 "B.Paste" user "Package Geometry/Pastemask Bottom")
		(5 "F.SilkS" user "Ref Des/Silkscreen Top")
		(7 "B.SilkS" user "Ref Des/Silkscreen Bottom")
		(1 "F.Mask" user "Board Geometry/Soldermask Top")
		(3 "B.Mask" user "Board Geometry/Soldermask Bottom")
		(17 "Dwgs.User" user "User.Drawings")
		(19 "Cmts.User" user "User.Comments")
		(21 "Eco1.User" user "User.Eco1")
		(23 "Eco2.User" user "User.Eco2")
		(25 "Edge.Cuts" user "Board Geometry/Outline")
		(27 "Margin" user)
		(31 "F.CrtYd" user "Package Geometry/Place Bound Top")
		(29 "B.CrtYd" user "Package Geometry/Place Bound Bottom")
		(35 "F.Fab" user "Ref Des/Assembly Top")
		(33 "B.Fab" user "Ref Des/Assembly Bottom")
	)
	(footprint ""
		(layer "F.Cu")
		(at 453.8472 -15.3924)
		(property "Reference" "C8F8"
			(at 0 0 0)
			(layer "F.SilkS")
			(hide yes)
			(effects
				(font
					(size 1.27 1.27)
				)
			)
		)
		(property "Value" "*"
			(at 0 -9.7155 0)
			(unlocked yes)
			(layer "F.Fab")
			(hide yes)
			(effects
				(font
					(size 1.27 1.016)
					(thickness 0.1524)
				)
			)
		)
		(property "Device Type" "ST470U6D3VDM-7-GP_SMD-TCG4-ST4A"
			(at 0 -11.2395 0)
			(unlocked yes)
			(layer "F.Fab")
			(hide yes)
			(effects
				(font
					(size 1.27 1.016)
					(thickness 0.1524)
				)
			)
		)
		(duplicate_pad_numbers_are_jumpers no)
		(fp_line
			(start -2.286 -4.8768)
			(end -2.286 -2.032)
			(stroke
				(width 0.1524)
				(type default)
			)
			(layer "F.SilkS")
		)
		(fp_line
			(start -2.286 4.8768)
			(end -2.286 2.032)
			(stroke
				(width 0.1524)
				(type default)
			)
			(layer "F.SilkS")
		)
		(fp_line
			(start 2.1082 -4.699)
			(end -2.1082 -4.699)
			(stroke
				(width 0.508)
				(type default)
			)
			(layer "F.SilkS")
		)
		(fp_line
			(start 2.286 -4.8768)
			(end -2.286 -4.8768)
			(stroke
				(width 0.1524)
				(type default)
			)
			(layer "F.SilkS")
		)
		(fp_line
			(start 2.286 -2.032)
			(end 2.286 -4.8768)
			(stroke
				(width 0.1524)
				(type default)
			)
			(layer "F.SilkS")
		)
		(fp_line
			(start 2.286 2.032)
			(end 2.286 4.8768)
			(stroke
				(width 0.1524)
				(type default)
			)
			(layer "F.SilkS")
		)
		(fp_line
			(start 2.286 4.8768)
			(end -2.286 4.8768)
			(stroke
				(width 0.1524)
				(type default)
			)
			(layer "F.SilkS")
		)
		(fp_rect
			(start -2.1463 3.6449)
			(end 2.1463 -3.6449)
			(stroke
				(width 0)
				(type default)
			)
			(fill no)
			(layer "F.CrtYd")
		)
		(fp_poly
			(pts
				(xy -2.54 4.953) (xy -2.54 4.2926) (xy -3.81 4.2926) (xy -3.81 -4.2926) (xy -2.54 -4.2926) (xy -2.54 -4.953)
				(xy 2.54 -4.953) (xy 2.54 -4.2926) (xy 3.81 -4.2926) (xy 3.81 -1.6256) (xy 2.1463 -1.6256) (xy 2.1463 -3.6449)
				(xy -2.1463 -3.6449) (xy -2.1463 3.6449) (xy 2.1463 3.6449) (xy 2.1463 -1.6129) (xy 3.81 -1.6129)
				(xy 3.81 4.2926) (xy 2.54 4.2926) (xy 2.54 4.953)
			)
			(stroke
				(width 0)
				(type default)
			)
			(fill no)
			(layer "F.CrtYd")
		)
		(fp_rect
			(start -3.81 4.2926)
			(end -2.54 -4.2926)
			(stroke
				(width 0)
				(type default)
			)
			(fill no)
			(layer "F.Fab")
		)
		(fp_rect
			(start -2.54 4.953)
			(end 2.54 -4.953)
			(stroke
				(width 0)
				(type default)
			)
			(fill no)
			(layer "F.Fab")
		)
		(fp_rect
			(start 2.54 4.2926)
			(end 3.81 -4.2926)
			(stroke
				(width 0)
				(type default)
			)
			(fill no)
			(layer "F.Fab")
		)
		(pad "1" smd rect
			(at 0 -3.1496)
			(size 2.413 2.286)
			(layers "F.Cu" "F.Mask" "F.Paste")
			(net "P3V3_STBY")
		)
		(pad "2" smd rect
			(at 0 3.1496)
			(size 2.413 2.286)
			(layers "F.Cu" "F.Mask" "F.Paste")
			(net "GND")
		)
		(zone
			(layer "F.Cu")
			(hatch none 0.5)
			(connect_pads
				(clearance 0)
			)
			(min_thickness 0.25)
			(keepout
				(tracks allowed)
				(vias not_allowed)
				(pads allowed)
				(copperpour not_allowed)
				(footprints allowed)
			)
			(placement
				(enabled no)
				(sheetname "")
			)
			(fill
				(thermal_gap 0.5)
				(thermal_bridge_width 0.5)
				(island_removal_mode 0)
			)
			(polygon
				(pts
					(xy 452.3359 -10.795) (xy 455.3585 -10.795) (xy 455.3585 -13.6906) (xy 455.3585 -14.0208) (xy 452.3359 -14.0208)
					(xy 452.3359 -13.6906)
				)
			)
		)
		(zone
			(layer "F.Cu")
			(hatch none 0.5)
			(connect_pads
				(clearance 0)
			)
			(min_thickness 0.25)
			(keepout
				(tracks allowed)
				(vias not_allowed)
				(pads allowed)
				(copperpour not_allowed)
				(footprints allowed)
			)
			(placement
				(enabled no)
				(sheetname "")
			)
			(fill
				(thermal_gap 0.5)
				(thermal_bridge_width 0.5)
				(island_removal_mode 0)
			)
			(polygon
				(pts
					(xy 455.3585 -17.0815) (xy 455.3585 -19.9898) (xy 452.3359 -19.9898) (xy 452.3359 -17.0942) (xy 452.3359 -16.764)
					(xy 455.3585 -16.764)
				)
			)
		)
	)
	(footprint ""
		(layer "F.Cu")
		(at 351.779332 3.530854 -90)
		(property "Reference" "C7G38"
			(at 0 0 270)
			(layer "F.SilkS")
			(hide yes)
			(effects
				(font
					(size 1.27 1.27)
				)
			)
		)
		(property "Value" ""
			(at 0 0 270)
			(layer "F.Fab")
			(effects
				(font
					(size 1.27 1.27)
				)
			)
		)
		(duplicate_pad_numbers_are_jumpers no)
		(fp_poly
			(pts
				(xy 0.3048 -0.1016) (xy 0.3048 0.9906) (xy -0.3048 0.9906) (xy -0.3048 -0.1016)
			)
			(stroke
				(width 0)
				(type default)
			)
			(fill no)
			(layer "F.CrtYd")
		)
		(fp_line
			(start -0.3048 0.9906)
			(end 0.3048 0.9906)
			(stroke
				(width 0.1)
				(type default)
			)
			(layer "F.Fab")
		)
		(fp_line
			(start 0.3048 0.9906)
			(end 0.3048 -0.1016)
			(stroke
				(width 0.1)
				(type default)
			)
			(layer "F.Fab")
		)
		(fp_line
			(start -0.3048 -0.1016)
			(end -0.3048 0.9906)
			(stroke
				(width 0.1)
				(type default)
			)
			(layer "F.Fab")
		)
		(fp_line
			(start 0.3048 -0.1016)
			(end -0.3048 -0.1016)
			(stroke
				(width 0.1)
				(type default)
			)
			(layer "F.Fab")
		)
		(pad "1" smd rect
			(at 0 0 270)
			(size 0.508 0.508)
			(layers "F.Cu" "F.Mask" "F.Paste")
			(net "VR_PVDDQ_ABC_PH2_BOOT")
		)
		(pad "2" smd rect
			(at 0 0.889 270)
			(size 0.508 0.508)
			(layers "F.Cu" "F.Mask" "F.Paste")
			(net "VR_PVDDQ_ABC_PH2_PHASE")
		)
		(zone
			(layer "F.Cu")
			(hatch none 0.5)
			(connect_pads
				(clearance 0)
			)
			(min_thickness 0.25)
			(keepout
				(tracks not_allowed)
				(vias allowed)
				(pads allowed)
				(copperpour not_allowed)
				(footprints allowed)
			)
			(placement
				(enabled no)
				(sheetname "")
			)
			(fill
				(thermal_gap 0.5)
				(thermal_bridge_width 0.5)
				(island_removal_mode 0)
			)
			(polygon
				(pts
					(xy 351.144332 3.276854) (xy 351.144332 3.784854) (xy 351.525332 3.784854) (xy 351.525332 3.276854)
				)
			)
		)
		(zone
			(layer "F.Cu")
			(hatch none 0.5)
			(connect_pads
				(clearance 0)
			)
			(min_thickness 0.25)
			(keepout
				(tracks allowed)
				(vias not_allowed)
				(pads allowed)
				(copperpour not_allowed)
				(footprints allowed)
			)
			(placement
				(enabled no)
				(sheetname "")
			)
			(fill
				(thermal_gap 0.5)
				(thermal_bridge_width 0.5)
				(island_removal_mode 0)
			)
			(polygon
				(pts
					(xy 351.525332 3.276854) (xy 351.525332 3.784854) (xy 351.144332 3.784854) (xy 351.144332 3.276854)
				)
			)
		)
	)
)
